(kicad_pcb
	(version 20260206)
	(generator "pcbnew")
	(generator_version "10.0")
	(general
		(thickness 1.6)
		(legacy_teardrops no)
	)
	(paper "A4")
	(title_block
		(title "Wiwynn_Tioga_Pass_MB.brd")
		(comment 1 "Tioga Pass / footprint 2141 of 4770 (J1G2), pads 244-291 of 291")
	)
	(layers
		(0 "F.Cu" signal "TOP")
		(4 "In1.Cu" signal "L2GND")
		(6 "In2.Cu" signal "L3")
		(8 "In3.Cu" signal "L4GND")
		(10 "In4.Cu" signal "L5")
		(12 "In5.Cu" signal "L6GND")
		(14 "In6.Cu" signal "L7VCC")
		(16 "In7.Cu" signal "L8VCC")
		(18 "In8.Cu" signal "L9GND")
		(20 "In9.Cu" signal "L10")
		(22 "In10.Cu" signal "L11GND")
		(24 "In11.Cu" signal "L12")
		(26 "In12.Cu" signal "L13GND")
		(2 "B.Cu" signal "BOTTOM")
		(9 "F.Adhes" user "F.Adhesive")
		(11 "B.Adhes" user "B.Adhesive")
		(13 "F.Paste" user "Package Geometry/Pastemask Top")
		(15 "B.Paste" user "Package Geometry/Pastemask Bottom")
		(5 "F.SilkS" user "Ref Des/Silkscreen Top")
		(7 "B.SilkS" user "Ref Des/Silkscreen Bottom")
		(1 "F.Mask" user "Board Geometry/Soldermask Top")
		(3 "B.Mask" user "Board Geometry/Soldermask Bottom")
		(17 "Dwgs.User" user "User.Drawings")
		(19 "Cmts.User" user "User.Comments")
		(21 "Eco1.User" user "User.Eco1")
		(23 "Eco2.User" user "User.Eco2")
		(25 "Edge.Cuts" user "Board Geometry/Outline")
		(27 "Margin" user)
		(31 "F.CrtYd" user "Package Geometry/Place Bound Top")
		(29 "B.CrtYd" user "Package Geometry/Place Bound Bottom")
		(35 "F.Fab" user "Ref Des/Assembly Top")
		(33 "B.Fab" user "Ref Des/Assembly Bottom")
	)
	(footprint ""
		(layer "F.Cu")
		(at 29.699458 -5.822442 90)
		(property "Reference" "J1G2"
			(at 7.104888 34.562542 0)
			(unlocked yes)
			(layer "F.SilkS")
			(effects
				(font
					(size 0.7874 0.5842)
					(thickness 0.1524)
				)
				(justify left)
			)
		)
		(property "Value" ""
			(at 0 0 90)
			(layer "F.Fab")
			(effects
				(font
					(size 1.27 1.27)
				)
			)
		)
		(duplicate_pad_numbers_are_jumpers no)
		(pad "241" smd rect
			(at 4.59994 86.700106 90)
			(size 1.8034 0.508)
			(layers "F.Cu" "F.Mask" "F.Paste")
			(net "GND")
		)
		(pad "242" smd rect
			(at 4.59994 87.54999 90)
			(size 1.8034 0.508)
			(layers "F.Cu" "F.Mask" "F.Paste")
			(net "M_H_DQ<32>")
		)
		(pad "243" smd rect
			(at 4.59994 88.399874 90)
			(size 1.8034 0.508)
			(layers "F.Cu" "F.Mask" "F.Paste")
			(net "GND")
		)
		(pad "244" smd rect
			(at 4.59994 89.250012 90)
			(size 1.8034 0.508)
			(layers "F.Cu" "F.Mask" "F.Paste")
			(net "M_H_DQS_DN<4>")
		)
		(pad "245" smd rect
			(at 4.59994 90.099896 90)
			(size 1.8034 0.508)
			(layers "F.Cu" "F.Mask" "F.Paste")
			(net "M_H_DQS_DP<4>")
		)
		(pad "246" smd rect
			(at 4.59994 90.950034 90)
			(size 1.8034 0.508)
			(layers "F.Cu" "F.Mask" "F.Paste")
			(net "GND")
		)
		(pad "247" smd rect
			(at 4.59994 91.799918 90)
			(size 1.8034 0.508)
			(layers "F.Cu" "F.Mask" "F.Paste")
			(net "M_H_DQ<38>")
		)
		(pad "248" smd rect
			(at 4.59994 92.650056 90)
			(size 1.8034 0.508)
			(layers "F.Cu" "F.Mask" "F.Paste")
			(net "GND")
		)
		(pad "249" smd rect
			(at 4.59994 93.49994 90)
			(size 1.8034 0.508)
			(layers "F.Cu" "F.Mask" "F.Paste")
			(net "M_H_DQ<34>")
		)
		(pad "250" smd rect
			(at 4.59994 94.350078 90)
			(size 1.8034 0.508)
			(layers "F.Cu" "F.Mask" "F.Paste")
			(net "GND")
		)
		(pad "251" smd rect
			(at 4.59994 95.199962 90)
			(size 1.8034 0.508)
			(layers "F.Cu" "F.Mask" "F.Paste")
			(net "M_H_DQ<44>")
		)
		(pad "252" smd rect
			(at 4.59994 96.0501 90)
			(size 1.8034 0.508)
			(layers "F.Cu" "F.Mask" "F.Paste")
			(net "GND")
		)
		(pad "253" smd rect
			(at 4.59994 96.899984 90)
			(size 1.8034 0.508)
			(layers "F.Cu" "F.Mask" "F.Paste")
			(net "M_H_DQ<40>")
		)
		(pad "254" smd rect
			(at 4.59994 97.750122 90)
			(size 1.8034 0.508)
			(layers "F.Cu" "F.Mask" "F.Paste")
			(net "GND")
		)
		(pad "255" smd rect
			(at 4.59994 98.600006 90)
			(size 1.8034 0.508)
			(layers "F.Cu" "F.Mask" "F.Paste")
			(net "M_H_DQS_DN<5>")
		)
		(pad "256" smd rect
			(at 4.59994 99.44989 90)
			(size 1.8034 0.508)
			(layers "F.Cu" "F.Mask" "F.Paste")
			(net "M_H_DQS_DP<5>")
		)
		(pad "257" smd rect
			(at 4.59994 100.300028 90)
			(size 1.8034 0.508)
			(layers "F.Cu" "F.Mask" "F.Paste")
			(net "GND")
		)
		(pad "258" smd rect
			(at 4.59994 101.149912 90)
			(size 1.8034 0.508)
			(layers "F.Cu" "F.Mask" "F.Paste")
			(net "M_H_DQ<46>")
		)
		(pad "259" smd rect
			(at 4.59994 102.00005 90)
			(size 1.8034 0.508)
			(layers "F.Cu" "F.Mask" "F.Paste")
			(net "GND")
		)
		(pad "260" smd rect
			(at 4.59994 102.849934 90)
			(size 1.8034 0.508)
			(layers "F.Cu" "F.Mask" "F.Paste")
			(net "M_H_DQ<42>")
		)
		(pad "261" smd rect
			(at 4.59994 103.700072 90)
			(size 1.8034 0.508)
			(layers "F.Cu" "F.Mask" "F.Paste")
			(net "GND")
		)
		(pad "262" smd rect
			(at 4.59994 104.549956 90)
			(size 1.8034 0.508)
			(layers "F.Cu" "F.Mask" "F.Paste")
			(net "M_H_DQ<52>")
		)
		(pad "263" smd rect
			(at 4.59994 105.400094 90)
			(size 1.8034 0.508)
			(layers "F.Cu" "F.Mask" "F.Paste")
			(net "GND")
		)
		(pad "264" smd rect
			(at 4.59994 106.249978 90)
			(size 1.8034 0.508)
			(layers "F.Cu" "F.Mask" "F.Paste")
			(net "M_H_DQ<48>")
		)
		(pad "265" smd rect
			(at 4.59994 107.100116 90)
			(size 1.8034 0.508)
			(layers "F.Cu" "F.Mask" "F.Paste")
			(net "GND")
		)
		(pad "266" smd rect
			(at 4.59994 107.95 90)
			(size 1.8034 0.508)
			(layers "F.Cu" "F.Mask" "F.Paste")
			(net "M_H_DQS_DN<6>")
		)
		(pad "267" smd rect
			(at 4.59994 108.799884 90)
			(size 1.8034 0.508)
			(layers "F.Cu" "F.Mask" "F.Paste")
			(net "M_H_DQS_DP<6>")
		)
		(pad "268" smd rect
			(at 4.59994 109.650022 90)
			(size 1.8034 0.508)
			(layers "F.Cu" "F.Mask" "F.Paste")
			(net "GND")
		)
		(pad "269" smd rect
			(at 4.59994 110.499906 90)
			(size 1.8034 0.508)
			(layers "F.Cu" "F.Mask" "F.Paste")
			(net "M_H_DQ<54>")
		)
		(pad "270" smd rect
			(at 4.59994 111.350044 90)
			(size 1.8034 0.508)
			(layers "F.Cu" "F.Mask" "F.Paste")
			(net "GND")
		)
		(pad "271" smd rect
			(at 4.59994 112.199928 90)
			(size 1.8034 0.508)
			(layers "F.Cu" "F.Mask" "F.Paste")
			(net "M_H_DQ<50>")
		)
		(pad "272" smd rect
			(at 4.59994 113.050066 90)
			(size 1.8034 0.508)
			(layers "F.Cu" "F.Mask" "F.Paste")
			(net "GND")
		)
		(pad "273" smd rect
			(at 4.59994 113.89995 90)
			(size 1.8034 0.508)
			(layers "F.Cu" "F.Mask" "F.Paste")
			(net "M_H_DQ<60>")
		)
		(pad "274" smd rect
			(at 4.59994 114.750088 90)
			(size 1.8034 0.508)
			(layers "F.Cu" "F.Mask" "F.Paste")
			(net "GND")
		)
		(pad "275" smd rect
			(at 4.59994 115.599972 90)
			(size 1.8034 0.508)
			(layers "F.Cu" "F.Mask" "F.Paste")
			(net "M_H_DQ<56>")
		)
		(pad "276" smd rect
			(at 4.59994 116.45011 90)
			(size 1.8034 0.508)
			(layers "F.Cu" "F.Mask" "F.Paste")
			(net "GND")
		)
		(pad "277" smd rect
			(at 4.59994 117.299994 90)
			(size 1.8034 0.508)
			(layers "F.Cu" "F.Mask" "F.Paste")
			(net "M_H_DQS_DN<7>")
		)
		(pad "278" smd rect
			(at 4.59994 118.149878 90)
			(size 1.8034 0.508)
			(layers "F.Cu" "F.Mask" "F.Paste")
			(net "M_H_DQS_DP<7>")
		)
		(pad "279" smd rect
			(at 4.59994 119.000016 90)
			(size 1.8034 0.508)
			(layers "F.Cu" "F.Mask" "F.Paste")
			(net "GND")
		)
		(pad "280" smd rect
			(at 4.59994 119.8499 90)
			(size 1.8034 0.508)
			(layers "F.Cu" "F.Mask" "F.Paste")
			(net "M_H_DQ<62>")
		)
		(pad "281" smd rect
			(at 4.59994 120.700038 90)
			(size 1.8034 0.508)
			(layers "F.Cu" "F.Mask" "F.Paste")
			(net "GND")
		)
		(pad "282" smd rect
			(at 4.59994 121.549922 90)
			(size 1.8034 0.508)
			(layers "F.Cu" "F.Mask" "F.Paste")
			(net "M_H_DQ<58>")
		)
		(pad "283" smd rect
			(at 4.59994 122.40006 90)
			(size 1.8034 0.508)
			(layers "F.Cu" "F.Mask" "F.Paste")
			(net "GND")
		)
		(pad "284" smd rect
			(at 4.59994 123.249944 90)
			(size 1.8034 0.508)
			(layers "F.Cu" "F.Mask" "F.Paste")
			(net "PVPP_GHJ")
		)
		(pad "285" smd rect
			(at 4.59994 124.100082 90)
			(size 1.8034 0.508)
			(layers "F.Cu" "F.Mask" "F.Paste")
			(net "SMB_DDR_GHJ_VPP_SDA")
		)
		(pad "286" smd rect
			(at 4.59994 124.949966 90)
			(size 1.8034 0.508)
			(layers "F.Cu" "F.Mask" "F.Paste")
			(net "PVPP_GHJ")
		)
		(pad "287" smd rect
			(at 4.59994 125.800104 90)
			(size 1.8034 0.508)
			(layers "F.Cu" "F.Mask" "F.Paste")
			(net "PVPP_GHJ")
		)
		(pad "288" smd rect
			(at 4.59994 126.649988 90)
			(size 1.8034 0.508)
			(layers "F.Cu" "F.Mask" "F.Paste")
			(net "PVPP_GHJ")
		)
	)
)
